(kicad_pcb
	(version 20260206)
	(generator "pcbnew")
	(generator_version "10.0")
	(general
		(thickness 1.6)
		(legacy_teardrops no)
	)
	(paper "A4")
	(title_block
		(title "9054_F0T_PDB_BD_GPU_F_V04_1213_1550_OCP.brd")
		(comment 1 "Grand Teton / footprints 564-569 of 608")
	)
	(layers
		(0 "F.Cu" signal "TOP")
		(4 "In1.Cu" signal "GND")
		(6 "In2.Cu" signal "IN1")
		(8 "In3.Cu" signal "GND1")
		(10 "In4.Cu" signal "VCC")
		(12 "In5.Cu" signal "VCC1")
		(14 "In6.Cu" signal "GND2")
		(16 "In7.Cu" signal "IN2")
		(18 "In8.Cu" signal "GND3")
		(2 "B.Cu" signal "BOTTOM")
		(9 "F.Adhes" user "F.Adhesive")
		(11 "B.Adhes" user "B.Adhesive")
		(13 "F.Paste" user "Package Geometry/Pastemask Top")
		(15 "B.Paste" user "Package Geometry/Pastemask Bottom")
		(5 "F.SilkS" user "Ref Des/Silkscreen Top")
		(7 "B.SilkS" user "Ref Des/Silkscreen Bottom")
		(1 "F.Mask" user "Board Geometry/Soldermask Top")
		(3 "B.Mask" user "Board Geometry/Soldermask Bottom")
		(17 "Dwgs.User" user "User.Drawings")
		(19 "Cmts.User" user "User.Comments")
		(21 "Eco1.User" user "User.Eco1")
		(23 "Eco2.User" user "User.Eco2")
		(25 "Edge.Cuts" user "Board Geometry/Outline")
		(27 "Margin" user)
		(31 "F.CrtYd" user "Package Geometry/Place Bound Top")
		(29 "B.CrtYd" user "Package Geometry/Place Bound Bottom")
		(35 "F.Fab" user "Ref Des/Assembly Top")
		(33 "B.Fab" user "Ref Des/Assembly Bottom")
	)
	(footprint ""
		(layer "B.Cu")
		(at 169.083736 -56.007 -90)
		(property "Reference" "PR7023"
			(at 0 0 90)
			(layer "B.SilkS")
			(hide yes)
			(effects
				(font
					(size 1.27 1.27)
				)
				(justify mirror)
			)
		)
		(property "Value" ""
			(at 0 0 90)
			(layer "B.Fab")
			(effects
				(font
					(size 1.27 1.27)
				)
				(justify mirror)
			)
		)
		(duplicate_pad_numbers_are_jumpers no)
		(fp_line
			(start -1.651 0.8382)
			(end 1.651 0.8382)
			(stroke
				(width 0.1524)
				(type default)
			)
			(layer "B.SilkS")
		)
		(fp_line
			(start 1.651 0.8382)
			(end 1.651 -0.8382)
			(stroke
				(width 0.1524)
				(type default)
			)
			(layer "B.SilkS")
		)
		(fp_line
			(start -1.651 -0.8382)
			(end -1.651 0.8382)
			(stroke
				(width 0.1524)
				(type default)
			)
			(layer "B.SilkS")
		)
		(fp_line
			(start 1.651 -0.8382)
			(end -1.651 -0.8382)
			(stroke
				(width 0.1524)
				(type default)
			)
			(layer "B.SilkS")
		)
		(fp_line
			(start -1.560576 0.7366)
			(end -1.560576 -0.7366)
			(stroke
				(width 0.1)
				(type default)
			)
			(layer "B.Fab")
		)
		(fp_line
			(start -1.524 0.7366)
			(end -1.560576 0.7366)
			(stroke
				(width 0.1)
				(type default)
			)
			(layer "B.Fab")
		)
		(fp_line
			(start 1.524 0.7366)
			(end -1.524 0.7366)
			(stroke
				(width 0.1)
				(type default)
			)
			(layer "B.Fab")
		)
		(fp_line
			(start 1.559814 0.7366)
			(end 1.524 0.7366)
			(stroke
				(width 0.1)
				(type default)
			)
			(layer "B.Fab")
		)
		(fp_line
			(start -1.560576 -0.7366)
			(end -1.524 -0.7366)
			(stroke
				(width 0.1)
				(type default)
			)
			(layer "B.Fab")
		)
		(fp_line
			(start -1.524 -0.7366)
			(end 1.524 -0.7366)
			(stroke
				(width 0.1)
				(type default)
			)
			(layer "B.Fab")
		)
		(fp_line
			(start 1.524 -0.7366)
			(end 1.559814 -0.7366)
			(stroke
				(width 0.1)
				(type default)
			)
			(layer "B.Fab")
		)
		(fp_line
			(start 1.559814 -0.7366)
			(end 1.559814 0.7366)
			(stroke
				(width 0.1)
				(type default)
			)
			(layer "B.Fab")
		)
		(pad "1" smd rect
			(at 0.94996 0 270)
			(size 1.1176 1.3716)
			(layers "B.Cu" "B.Mask" "B.Paste")
			(net "P52V_2")
		)
		(pad "2" smd rect
			(at -0.94996 0 270)
			(size 1.1176 1.3716)
			(layers "B.Cu" "B.Mask" "B.Paste")
			(net "P52V_HS2_ISET")
		)
	)
	(footprint ""
		(layer "B.Cu")
		(at 279.5524 -79.248)
		(property "Reference" "PR19"
			(at 0 0 0)
			(layer "B.SilkS")
			(hide yes)
			(effects
				(font
					(size 1.27 1.27)
				)
				(justify mirror)
			)
		)
		(property "Value" ""
			(at 0 0 0)
			(layer "B.Fab")
			(effects
				(font
					(size 1.27 1.27)
				)
				(justify mirror)
			)
		)
		(duplicate_pad_numbers_are_jumpers no)
		(fp_line
			(start -1.651 -0.8382)
			(end -1.651 0.8382)
			(stroke
				(width 0.1524)
				(type default)
			)
			(layer "B.SilkS")
		)
		(fp_line
			(start -1.651 0.8382)
			(end 1.651 0.8382)
			(stroke
				(width 0.1524)
				(type default)
			)
			(layer "B.SilkS")
		)
		(fp_line
			(start 1.651 -0.8382)
			(end -1.651 -0.8382)
			(stroke
				(width 0.1524)
				(type default)
			)
			(layer "B.SilkS")
		)
		(fp_line
			(start 1.651 0.8382)
			(end 1.651 -0.8382)
			(stroke
				(width 0.1524)
				(type default)
			)
			(layer "B.SilkS")
		)
		(fp_line
			(start -1.560576 -0.7366)
			(end -1.524 -0.7366)
			(stroke
				(width 0.1)
				(type default)
			)
			(layer "B.Fab")
		)
		(fp_line
			(start -1.560576 0.7366)
			(end -1.560576 -0.7366)
			(stroke
				(width 0.1)
				(type default)
			)
			(layer "B.Fab")
		)
		(fp_line
			(start -1.524 -0.7366)
			(end 1.524 -0.7366)
			(stroke
				(width 0.1)
				(type default)
			)
			(layer "B.Fab")
		)
		(fp_line
			(start -1.524 0.7366)
			(end -1.560576 0.7366)
			(stroke
				(width 0.1)
				(type default)
			)
			(layer "B.Fab")
		)
		(fp_line
			(start 1.524 -0.7366)
			(end 1.559814 -0.7366)
			(stroke
				(width 0.1)
				(type default)
			)
			(layer "B.Fab")
		)
		(fp_line
			(start 1.524 0.7366)
			(end -1.524 0.7366)
			(stroke
				(width 0.1)
				(type default)
			)
			(layer "B.Fab")
		)
		(fp_line
			(start 1.559814 -0.7366)
			(end 1.559814 0.7366)
			(stroke
				(width 0.1)
				(type default)
			)
			(layer "B.Fab")
		)
		(fp_line
			(start 1.559814 0.7366)
			(end 1.524 0.7366)
			(stroke
				(width 0.1)
				(type default)
			)
			(layer "B.Fab")
		)
		(pad "1" smd rect
			(at 0.94996 0)
			(size 1.1176 1.3716)
			(layers "B.Cu" "B.Mask" "B.Paste")
			(net "P52V_HS1")
		)
		(pad "2" smd rect
			(at -0.94996 0)
			(size 1.1176 1.3716)
			(layers "B.Cu" "B.Mask" "B.Paste")
			(net "P52V_HS1_ISET")
		)
	)
	(footprint ""
		(layer "B.Cu")
		(at 169.210736 -71.247 180)
		(property "Reference" "R5886"
			(at 0 0 0)
			(layer "B.SilkS")
			(hide yes)
			(effects
				(font
					(size 1.27 1.27)
				)
				(justify mirror)
			)
		)
		(property "Value" ""
			(at 0 0 0)
			(layer "B.Fab")
			(effects
				(font
					(size 1.27 1.27)
				)
				(justify mirror)
			)
		)
		(duplicate_pad_numbers_are_jumpers no)
		(fp_line
			(start 0.7874 0.4064)
			(end 0.7874 -0.4064)
			(stroke
				(width 0.1524)
				(type default)
			)
			(layer "B.SilkS")
		)
		(fp_line
			(start 0.7874 -0.4064)
			(end -0.7874 -0.4064)
			(stroke
				(width 0.1524)
				(type default)
			)
			(layer "B.SilkS")
		)
		(fp_line
			(start -0.7874 0.4064)
			(end 0.7874 0.4064)
			(stroke
				(width 0.1524)
				(type default)
			)
			(layer "B.SilkS")
		)
		(fp_line
			(start -0.7874 -0.4064)
			(end -0.7874 0.4064)
			(stroke
				(width 0.1524)
				(type default)
			)
			(layer "B.SilkS")
		)
		(fp_line
			(start 0.67945 0.3048)
			(end 0.67945 -0.305054)
			(stroke
				(width 0.1)
				(type default)
			)
			(layer "B.Fab")
		)
		(fp_line
			(start 0.67945 -0.305054)
			(end 0.12065 -0.305054)
			(stroke
				(width 0.1)
				(type default)
			)
			(layer "B.Fab")
		)
		(fp_line
			(start 0.12065 0.3048)
			(end 0.67945 0.3048)
			(stroke
				(width 0.1)
				(type default)
			)
			(layer "B.Fab")
		)
		(fp_line
			(start 0.12065 0.2794)
			(end 0.12065 0.3048)
			(stroke
				(width 0.1)
				(type default)
			)
			(layer "B.Fab")
		)
		(fp_line
			(start 0.12065 -0.2794)
			(end -0.12065 -0.2794)
			(stroke
				(width 0.1)
				(type default)
			)
			(layer "B.Fab")
		)
		(fp_line
			(start 0.12065 -0.305054)
			(end 0.12065 -0.2794)
			(stroke
				(width 0.1)
				(type default)
			)
			(layer "B.Fab")
		)
		(fp_line
			(start -0.120396 0.3048)
			(end -0.120396 0.2794)
			(stroke
				(width 0.1)
				(type default)
			)
			(layer "B.Fab")
		)
		(fp_line
			(start -0.120396 0.2794)
			(end 0.12065 0.2794)
			(stroke
				(width 0.1)
				(type default)
			)
			(layer "B.Fab")
		)
		(fp_line
			(start -0.12065 -0.2794)
			(end -0.12065 -0.3048)
			(stroke
				(width 0.1)
				(type default)
			)
			(layer "B.Fab")
		)
		(fp_line
			(start -0.12065 -0.3048)
			(end -0.67945 -0.3048)
			(stroke
				(width 0.1)
				(type default)
			)
			(layer "B.Fab")
		)
		(fp_line
			(start -0.67945 0.3048)
			(end -0.120396 0.3048)
			(stroke
				(width 0.1)
				(type default)
			)
			(layer "B.Fab")
		)
		(fp_line
			(start -0.67945 -0.3048)
			(end -0.67945 0.3048)
			(stroke
				(width 0.1)
				(type default)
			)
			(layer "B.Fab")
		)
		(pad "1" smd circle
			(at 0.40005 0)
			(size 0 0)
			(layers "B.Cu" "B.Mask" "B.Paste")
			(net "SMB_P52V_PDB_SCL")
		)
		(pad "2" smd circle
			(at -0.40005 0)
			(size 0 0)
			(layers "B.Cu" "B.Mask" "B.Paste")
			(net "SMB_P52V_PDB_SCL_R2")
		)
	)
	(footprint ""
		(layer "B.Cu")
		(at 417.900358 -32.759396 90)
		(property "Reference" "C101"
			(at 0 0 90)
			(layer "B.SilkS")
			(hide yes)
			(effects
				(font
					(size 1.27 1.27)
				)
				(justify mirror)
			)
		)
		(property "Value" ""
			(at 0 0 90)
			(layer "B.Fab")
			(effects
				(font
					(size 1.27 1.27)
				)
				(justify mirror)
			)
		)
		(duplicate_pad_numbers_are_jumpers no)
		(fp_line
			(start 0.7874 -0.4064)
			(end -0.7874 -0.4064)
			(stroke
				(width 0.1524)
				(type default)
			)
			(layer "B.SilkS")
		)
		(fp_line
			(start -0.7874 -0.4064)
			(end -0.7874 0.4064)
			(stroke
				(width 0.1524)
				(type default)
			)
			(layer "B.SilkS")
		)
		(fp_line
			(start 0.7874 0.4064)
			(end 0.7874 -0.4064)
			(stroke
				(width 0.1524)
				(type default)
			)
			(layer "B.SilkS")
		)
		(fp_line
			(start -0.7874 0.4064)
			(end 0.7874 0.4064)
			(stroke
				(width 0.1524)
				(type default)
			)
			(layer "B.SilkS")
		)
		(fp_line
			(start 0.67945 -0.305054)
			(end 0.12065 -0.305054)
			(stroke
				(width 0.1)
				(type default)
			)
			(layer "B.Fab")
		)
		(fp_line
			(start 0.12065 -0.305054)
			(end 0.12065 -0.2794)
			(stroke
				(width 0.1)
				(type default)
			)
			(layer "B.Fab")
		)
		(fp_line
			(start -0.12065 -0.3048)
			(end -0.67945 -0.3048)
			(stroke
				(width 0.1)
				(type default)
			)
			(layer "B.Fab")
		)
		(fp_line
			(start -0.67945 -0.3048)
			(end -0.67945 0.3048)
			(stroke
				(width 0.1)
				(type default)
			)
			(layer "B.Fab")
		)
		(fp_line
			(start 0.12065 -0.2794)
			(end -0.12065 -0.2794)
			(stroke
				(width 0.1)
				(type default)
			)
			(layer "B.Fab")
		)
		(fp_line
			(start -0.12065 -0.2794)
			(end -0.12065 -0.3048)
			(stroke
				(width 0.1)
				(type default)
			)
			(layer "B.Fab")
		)
		(fp_line
			(start 0.12065 0.2794)
			(end 0.12065 0.3048)
			(stroke
				(width 0.1)
				(type default)
			)
			(layer "B.Fab")
		)
		(fp_line
			(start -0.120396 0.2794)
			(end 0.12065 0.2794)
			(stroke
				(width 0.1)
				(type default)
			)
			(layer "B.Fab")
		)
		(fp_line
			(start 0.67945 0.3048)
			(end 0.67945 -0.305054)
			(stroke
				(width 0.1)
				(type default)
			)
			(layer "B.Fab")
		)
		(fp_line
			(start 0.12065 0.3048)
			(end 0.67945 0.3048)
			(stroke
				(width 0.1)
				(type default)
			)
			(layer "B.Fab")
		)
		(fp_line
			(start -0.120396 0.3048)
			(end -0.120396 0.2794)
			(stroke
				(width 0.1)
				(type default)
			)
			(layer "B.Fab")
		)
		(fp_line
			(start -0.67945 0.3048)
			(end -0.120396 0.3048)
			(stroke
				(width 0.1)
				(type default)
			)
			(layer "B.Fab")
		)
		(pad "1" smd circle
			(at 0.40005 0 270)
			(size 0 0)
			(layers "B.Cu" "B.Mask" "B.Paste")
			(net "P12V_LED_ISET_R")
		)
		(pad "2" smd circle
			(at -0.40005 0 270)
			(size 0 0)
			(layers "B.Cu" "B.Mask" "B.Paste")
			(net "GND")
		)
	)
	(footprint ""
		(layer "B.Cu")
		(at 161.336736 -70.866 90)
		(property "Reference" "PR7014"
			(at 0 0 90)
			(layer "B.SilkS")
			(hide yes)
			(effects
				(font
					(size 1.27 1.27)
				)
				(justify mirror)
			)
		)
		(property "Value" ""
			(at 0 0 90)
			(layer "B.Fab")
			(effects
				(font
					(size 1.27 1.27)
				)
				(justify mirror)
			)
		)
		(duplicate_pad_numbers_are_jumpers no)
		(fp_line
			(start 0.7874 -0.4064)
			(end -0.7874 -0.4064)
			(stroke
				(width 0.1524)
				(type default)
			)
			(layer "B.SilkS")
		)
		(fp_line
			(start -0.7874 -0.4064)
			(end -0.7874 0.4064)
			(stroke
				(width 0.1524)
				(type default)
			)
			(layer "B.SilkS")
		)
		(fp_line
			(start 0.7874 0.4064)
			(end 0.7874 -0.4064)
			(stroke
				(width 0.1524)
				(type default)
			)
			(layer "B.SilkS")
		)
		(fp_line
			(start -0.7874 0.4064)
			(end 0.7874 0.4064)
			(stroke
				(width 0.1524)
				(type default)
			)
			(layer "B.SilkS")
		)
		(fp_line
			(start 0.67945 -0.305054)
			(end 0.12065 -0.305054)
			(stroke
				(width 0.1)
				(type default)
			)
			(layer "B.Fab")
		)
		(fp_line
			(start 0.12065 -0.305054)
			(end 0.12065 -0.2794)
			(stroke
				(width 0.1)
				(type default)
			)
			(layer "B.Fab")
		)
		(fp_line
			(start -0.12065 -0.3048)
			(end -0.67945 -0.3048)
			(stroke
				(width 0.1)
				(type default)
			)
			(layer "B.Fab")
		)
		(fp_line
			(start -0.67945 -0.3048)
			(end -0.67945 0.3048)
			(stroke
				(width 0.1)
				(type default)
			)
			(layer "B.Fab")
		)
		(fp_line
			(start 0.12065 -0.2794)
			(end -0.12065 -0.2794)
			(stroke
				(width 0.1)
				(type default)
			)
			(layer "B.Fab")
		)
		(fp_line
			(start -0.12065 -0.2794)
			(end -0.12065 -0.3048)
			(stroke
				(width 0.1)
				(type default)
			)
			(layer "B.Fab")
		)
		(fp_line
			(start 0.12065 0.2794)
			(end 0.12065 0.3048)
			(stroke
				(width 0.1)
				(type default)
			)
			(layer "B.Fab")
		)
		(fp_line
			(start -0.120396 0.2794)
			(end 0.12065 0.2794)
			(stroke
				(width 0.1)
				(type default)
			)
			(layer "B.Fab")
		)
		(fp_line
			(start 0.67945 0.3048)
			(end 0.67945 -0.305054)
			(stroke
				(width 0.1)
				(type default)
			)
			(layer "B.Fab")
		)
		(fp_line
			(start 0.12065 0.3048)
			(end 0.67945 0.3048)
			(stroke
				(width 0.1)
				(type default)
			)
			(layer "B.Fab")
		)
		(fp_line
			(start -0.120396 0.3048)
			(end -0.120396 0.2794)
			(stroke
				(width 0.1)
				(type default)
			)
			(layer "B.Fab")
		)
		(fp_line
			(start -0.67945 0.3048)
			(end -0.120396 0.3048)
			(stroke
				(width 0.1)
				(type default)
			)
			(layer "B.Fab")
		)
		(pad "1" smd circle
			(at 0.40005 0 270)
			(size 0 0)
			(layers "B.Cu" "B.Mask" "B.Paste")
			(net "P52V_HS2_INTVCC")
		)
		(pad "2" smd circle
			(at -0.40005 0 270)
			(size 0 0)
			(layers "B.Cu" "B.Mask" "B.Paste")
			(net "P52V_HS2_SCK")
		)
	)
	(footprint ""
		(layer "B.Cu")
		(at 441.325 -47.371 180)
		(property "Reference" "R5941"
			(at 0 0 0)
			(layer "B.SilkS")
			(hide yes)
			(effects
				(font
					(size 1.27 1.27)
				)
				(justify mirror)
			)
		)
		(property "Value" ""
			(at 0 0 0)
			(layer "B.Fab")
			(effects
				(font
					(size 1.27 1.27)
				)
				(justify mirror)
			)
		)
		(duplicate_pad_numbers_are_jumpers no)
		(fp_line
			(start 0.7874 0.4064)
			(end 0.7874 -0.4064)
			(stroke
				(width 0.1524)
				(type default)
			)
			(layer "B.SilkS")
		)
		(fp_line
			(start 0.7874 -0.4064)
			(end -0.7874 -0.4064)
			(stroke
				(width 0.1524)
				(type default)
			)
			(layer "B.SilkS")
		)
		(fp_line
			(start -0.7874 0.4064)
			(end 0.7874 0.4064)
			(stroke
				(width 0.1524)
				(type default)
			)
			(layer "B.SilkS")
		)
		(fp_line
			(start -0.7874 -0.4064)
			(end -0.7874 0.4064)
			(stroke
				(width 0.1524)
				(type default)
			)
			(layer "B.SilkS")
		)
		(fp_line
			(start 0.67945 0.3048)
			(end 0.67945 -0.305054)
			(stroke
				(width 0.1)
				(type default)
			)
			(layer "B.Fab")
		)
		(fp_line
			(start 0.67945 -0.305054)
			(end 0.12065 -0.305054)
			(stroke
				(width 0.1)
				(type default)
			)
			(layer "B.Fab")
		)
		(fp_line
			(start 0.12065 0.3048)
			(end 0.67945 0.3048)
			(stroke
				(width 0.1)
				(type default)
			)
			(layer "B.Fab")
		)
		(fp_line
			(start 0.12065 0.2794)
			(end 0.12065 0.3048)
			(stroke
				(width 0.1)
				(type default)
			)
			(layer "B.Fab")
		)
		(fp_line
			(start 0.12065 -0.2794)
			(end -0.12065 -0.2794)
			(stroke
				(width 0.1)
				(type default)
			)
			(layer "B.Fab")
		)
		(fp_line
			(start 0.12065 -0.305054)
			(end 0.12065 -0.2794)
			(stroke
				(width 0.1)
				(type default)
			)
			(layer "B.Fab")
		)
		(fp_line
			(start -0.120396 0.3048)
			(end -0.120396 0.2794)
			(stroke
				(width 0.1)
				(type default)
			)
			(layer "B.Fab")
		)
		(fp_line
			(start -0.120396 0.2794)
			(end 0.12065 0.2794)
			(stroke
				(width 0.1)
				(type default)
			)
			(layer "B.Fab")
		)
		(fp_line
			(start -0.12065 -0.2794)
			(end -0.12065 -0.3048)
			(stroke
				(width 0.1)
				(type default)
			)
			(layer "B.Fab")
		)
		(fp_line
			(start -0.12065 -0.3048)
			(end -0.67945 -0.3048)
			(stroke
				(width 0.1)
				(type default)
			)
			(layer "B.Fab")
		)
		(fp_line
			(start -0.67945 0.3048)
			(end -0.120396 0.3048)
			(stroke
				(width 0.1)
				(type default)
			)
			(layer "B.Fab")
		)
		(fp_line
			(start -0.67945 -0.3048)
			(end -0.67945 0.3048)
			(stroke
				(width 0.1)
				(type default)
			)
			(layer "B.Fab")
		)
		(pad "1" smd circle
			(at 0.40005 0)
			(size 0 0)
			(layers "B.Cu" "B.Mask" "B.Paste")
			(net "P3V3_HPDB_PG")
		)
		(pad "2" smd circle
			(at -0.40005 0)
			(size 0 0)
			(layers "B.Cu" "B.Mask" "B.Paste")
			(net "P3V3_HPDB_PG_R1")
		)
	)
)
